(kicad_pcb
	(version 20260206)
	(generator "pcbnew")
	(generator_version "10.0")
	(general
		(thickness 1.6)
		(legacy_teardrops no)
	)
	(paper "A4")
	(title_block
		(title "01162023_DA0F0TEBIF0_F0T_Expander_BD_F_brd_V02_OCP.brd")
		(comment 1 "Grand Teton / footprints 9122-9128 of 9728")
	)
	(layers
		(0 "F.Cu" signal "TOP")
		(4 "In1.Cu" signal "GND")
		(6 "In2.Cu" signal "VCC")
		(8 "In3.Cu" signal "VCC1")
		(10 "In4.Cu" signal "GND1")
		(12 "In5.Cu" signal "IN1")
		(14 "In6.Cu" signal "GND2")
		(16 "In7.Cu" signal "IN2")
		(18 "In8.Cu" signal "GND3")
		(20 "In9.Cu" signal "IN3")
		(22 "In10.Cu" signal "GND4")
		(24 "In11.Cu" signal "IN4")
		(26 "In12.Cu" signal "GND5")
		(28 "In13.Cu" signal "IN5")
		(30 "In14.Cu" signal "GND6")
		(32 "In15.Cu" signal "IN6")
		(34 "In16.Cu" signal "GND7")
		(2 "B.Cu" signal "BOTTOM")
		(9 "F.Adhes" user "F.Adhesive")
		(11 "B.Adhes" user "B.Adhesive")
		(13 "F.Paste" user "Package Geometry/Pastemask Top")
		(15 "B.Paste" user "Package Geometry/Pastemask Bottom")
		(5 "F.SilkS" user "Ref Des/Silkscreen Top")
		(7 "B.SilkS" user "Ref Des/Silkscreen Bottom")
		(1 "F.Mask" user "Board Geometry/Soldermask Top")
		(3 "B.Mask" user "Board Geometry/Soldermask Bottom")
		(17 "Dwgs.User" user "User.Drawings")
		(19 "Cmts.User" user "User.Comments")
		(21 "Eco1.User" user "User.Eco1")
		(23 "Eco2.User" user "User.Eco2")
		(25 "Edge.Cuts" user "Board Geometry/Outline")
		(27 "Margin" user)
		(31 "F.CrtYd" user "Package Geometry/Place Bound Top")
		(29 "B.CrtYd" user "Package Geometry/Place Bound Bottom")
		(35 "F.Fab" user "Ref Des/Assembly Top")
		(33 "B.Fab" user "Ref Des/Assembly Bottom")
	)
	(footprint ""
		(layer "B.Cu")
		(at 417.54933 -115.613434 -90)
		(property "Reference" "U43"
			(at -1.658874 4.103878 0)
			(unlocked yes)
			(layer "B.SilkS")
			(effects
				(font
					(size 0.7874 0.5842)
					(thickness 0.1524)
				)
				(justify mirror)
			)
		)
		(property "Value" ""
			(at 0 0 90)
			(layer "B.Fab")
			(effects
				(font
					(size 1.27 1.27)
				)
				(justify mirror)
			)
		)
		(duplicate_pad_numbers_are_jumpers no)
		(fp_line
			(start -1.3462 1.1938)
			(end -1.3462 -1.1938)
			(stroke
				(width 0.1524)
				(type default)
			)
			(layer "B.SilkS")
		)
		(fp_line
			(start 1.3462 1.1938)
			(end -1.3462 1.1938)
			(stroke
				(width 0.1524)
				(type default)
			)
			(layer "B.SilkS")
		)
		(fp_line
			(start -1.3462 -1.1938)
			(end 1.3462 -1.1938)
			(stroke
				(width 0.1524)
				(type default)
			)
			(layer "B.SilkS")
		)
		(fp_line
			(start 1.3462 -1.1938)
			(end 1.3462 1.1684)
			(stroke
				(width 0.1524)
				(type default)
			)
			(layer "B.SilkS")
		)
		(fp_poly
			(pts
				(xy 1.447038 -0.760476) (xy 2.052066 -0.457962) (xy 2.052066 -1.06299)
			)
			(stroke
				(width 0)
				(type default)
			)
			(fill yes)
			(layer "B.SilkS")
		)
		(fp_line
			(start -0.674878 1.124966)
			(end -0.674878 -1.124966)
			(stroke
				(width 0.1)
				(type default)
			)
			(layer "B.Fab")
		)
		(fp_line
			(start 0.674878 1.124966)
			(end -0.674878 1.124966)
			(stroke
				(width 0.1)
				(type default)
			)
			(layer "B.Fab")
		)
		(fp_line
			(start -0.674878 -1.124966)
			(end 0.674878 -1.124966)
			(stroke
				(width 0.1)
				(type default)
			)
			(layer "B.Fab")
		)
		(fp_line
			(start 0.674878 -1.124966)
			(end 0.674878 1.124966)
			(stroke
				(width 0.1)
				(type default)
			)
			(layer "B.Fab")
		)
		(fp_poly
			(pts
				(xy 1.447038 -0.760476) (xy 2.052066 -0.457962) (xy 2.052066 -1.06299)
			)
			(stroke
				(width 0)
				(type default)
			)
			(fill yes)
			(layer "B.Fab")
		)
		(pad "1" smd rect
			(at 0.899922 -0.750062 90)
			(size 0.6096 0.6096)
			(layers "B.Cu" "B.Mask" "B.Paste")
			(net "NIC7_AUX_PWR_EN_R")
		)
		(pad "2" smd rect
			(at 0.899922 0)
			(size 0.4064 0.6096)
			(layers "B.Cu" "B.Mask" "B.Paste")
			(net "RST_SMB_NIC7_MUX_N")
		)
		(pad "3" smd rect
			(at 0.899922 0.750062 90)
			(size 0.6096 0.6096)
			(layers "B.Cu" "B.Mask" "B.Paste")
			(net "GND")
		)
		(pad "4" smd rect
			(at -0.899922 0.750062 90)
			(size 0.6096 0.6096)
			(layers "B.Cu" "B.Mask" "B.Paste")
			(net "RST_SMB_NIC7_MUX_ISO_N")
		)
		(pad "5" smd rect
			(at -0.899922 -0.750062 90)
			(size 0.6096 0.6096)
			(layers "B.Cu" "B.Mask" "B.Paste")
			(net "P3V3_AUX")
		)
	)
	(footprint ""
		(layer "B.Cu")
		(at 272.849848 -288.774886 -90)
		(property "Reference" "R3470"
			(at 0 0 90)
			(layer "B.SilkS")
			(hide yes)
			(effects
				(font
					(size 1.27 1.27)
				)
				(justify mirror)
			)
		)
		(property "Value" ""
			(at 0 0 90)
			(layer "B.Fab")
			(effects
				(font
					(size 1.27 1.27)
				)
				(justify mirror)
			)
		)
		(duplicate_pad_numbers_are_jumpers no)
		(fp_line
			(start -0.7874 0.4064)
			(end 0.7874 0.4064)
			(stroke
				(width 0.1524)
				(type default)
			)
			(layer "B.SilkS")
		)
		(fp_line
			(start 0.7874 0.4064)
			(end 0.7874 -0.4064)
			(stroke
				(width 0.1524)
				(type default)
			)
			(layer "B.SilkS")
		)
		(fp_line
			(start -0.7874 -0.4064)
			(end -0.7874 0.4064)
			(stroke
				(width 0.1524)
				(type default)
			)
			(layer "B.SilkS")
		)
		(fp_line
			(start 0.7874 -0.4064)
			(end -0.7874 -0.4064)
			(stroke
				(width 0.1524)
				(type default)
			)
			(layer "B.SilkS")
		)
		(fp_line
			(start -0.67945 0.3048)
			(end -0.120396 0.3048)
			(stroke
				(width 0.1)
				(type default)
			)
			(layer "B.Fab")
		)
		(fp_line
			(start -0.120396 0.3048)
			(end -0.120396 0.2794)
			(stroke
				(width 0.1)
				(type default)
			)
			(layer "B.Fab")
		)
		(fp_line
			(start 0.12065 0.3048)
			(end 0.67945 0.3048)
			(stroke
				(width 0.1)
				(type default)
			)
			(layer "B.Fab")
		)
		(fp_line
			(start 0.67945 0.3048)
			(end 0.67945 -0.305054)
			(stroke
				(width 0.1)
				(type default)
			)
			(layer "B.Fab")
		)
		(fp_line
			(start -0.120396 0.2794)
			(end 0.12065 0.2794)
			(stroke
				(width 0.1)
				(type default)
			)
			(layer "B.Fab")
		)
		(fp_line
			(start 0.12065 0.2794)
			(end 0.12065 0.3048)
			(stroke
				(width 0.1)
				(type default)
			)
			(layer "B.Fab")
		)
		(fp_line
			(start -0.12065 -0.2794)
			(end -0.12065 -0.3048)
			(stroke
				(width 0.1)
				(type default)
			)
			(layer "B.Fab")
		)
		(fp_line
			(start 0.12065 -0.2794)
			(end -0.12065 -0.2794)
			(stroke
				(width 0.1)
				(type default)
			)
			(layer "B.Fab")
		)
		(fp_line
			(start -0.67945 -0.3048)
			(end -0.67945 0.3048)
			(stroke
				(width 0.1)
				(type default)
			)
			(layer "B.Fab")
		)
		(fp_line
			(start -0.12065 -0.3048)
			(end -0.67945 -0.3048)
			(stroke
				(width 0.1)
				(type default)
			)
			(layer "B.Fab")
		)
		(fp_line
			(start 0.12065 -0.305054)
			(end 0.12065 -0.2794)
			(stroke
				(width 0.1)
				(type default)
			)
			(layer "B.Fab")
		)
		(fp_line
			(start 0.67945 -0.305054)
			(end 0.12065 -0.305054)
			(stroke
				(width 0.1)
				(type default)
			)
			(layer "B.Fab")
		)
		(pad "1" smd circle
			(at 0.40005 0 90)
			(size 0 0)
			(layers "B.Cu" "B.Mask" "B.Paste")
			(net "SPI_PEX2_CS_R_N")
		)
		(pad "2" smd circle
			(at -0.40005 0 90)
			(size 0 0)
			(layers "B.Cu" "B.Mask" "B.Paste")
			(net "SPI_PEX2_CS_N")
		)
	)
	(footprint ""
		(layer "B.Cu")
		(at 118.425214 -308.580028 90)
		(property "Reference" "C1414"
			(at 0 0 90)
			(layer "B.SilkS")
			(hide yes)
			(effects
				(font
					(size 1.27 1.27)
				)
				(justify mirror)
			)
		)
		(property "Value" ""
			(at 0 0 90)
			(layer "B.Fab")
			(effects
				(font
					(size 1.27 1.27)
				)
				(justify mirror)
			)
		)
		(duplicate_pad_numbers_are_jumpers no)
		(fp_line
			(start 1.2954 -0.5842)
			(end -1.2954 -0.5842)
			(stroke
				(width 0.1524)
				(type default)
			)
			(layer "B.SilkS")
		)
		(fp_line
			(start -1.2954 -0.5842)
			(end -1.2954 0.5842)
			(stroke
				(width 0.1524)
				(type default)
			)
			(layer "B.SilkS")
		)
		(fp_line
			(start 1.2954 0.5842)
			(end 1.2954 -0.5842)
			(stroke
				(width 0.1524)
				(type default)
			)
			(layer "B.SilkS")
		)
		(fp_line
			(start -1.2954 0.5842)
			(end 1.2954 0.5842)
			(stroke
				(width 0.1524)
				(type default)
			)
			(layer "B.SilkS")
		)
		(fp_line
			(start 0.8636 -0.4572)
			(end -0.8636 -0.4572)
			(stroke
				(width 0.1)
				(type default)
			)
			(layer "B.Fab")
		)
		(fp_line
			(start -0.8636 -0.4572)
			(end -0.8636 -0.4064)
			(stroke
				(width 0.1)
				(type default)
			)
			(layer "B.Fab")
		)
		(fp_line
			(start 1.1938 -0.4064)
			(end 0.8636 -0.4064)
			(stroke
				(width 0.1)
				(type default)
			)
			(layer "B.Fab")
		)
		(fp_line
			(start 0.8636 -0.4064)
			(end 0.8636 -0.4572)
			(stroke
				(width 0.1)
				(type default)
			)
			(layer "B.Fab")
		)
		(fp_line
			(start -0.8636 -0.4064)
			(end -1.1938 -0.4064)
			(stroke
				(width 0.1)
				(type default)
			)
			(layer "B.Fab")
		)
		(fp_line
			(start -1.1938 -0.4064)
			(end -1.1938 0.4064)
			(stroke
				(width 0.1)
				(type default)
			)
			(layer "B.Fab")
		)
		(fp_line
			(start 1.1938 0.4064)
			(end 1.1938 -0.4064)
			(stroke
				(width 0.1)
				(type default)
			)
			(layer "B.Fab")
		)
		(fp_line
			(start 0.8636 0.4064)
			(end 1.1938 0.4064)
			(stroke
				(width 0.1)
				(type default)
			)
			(layer "B.Fab")
		)
		(fp_line
			(start -0.8636 0.4064)
			(end -0.8636 0.4572)
			(stroke
				(width 0.1)
				(type default)
			)
			(layer "B.Fab")
		)
		(fp_line
			(start -1.1938 0.4064)
			(end -0.8636 0.4064)
			(stroke
				(width 0.1)
				(type default)
			)
			(layer "B.Fab")
		)
		(fp_line
			(start 0.8636 0.4572)
			(end 0.8636 0.4064)
			(stroke
				(width 0.1)
				(type default)
			)
			(layer "B.Fab")
		)
		(fp_line
			(start -0.8636 0.4572)
			(end 0.8636 0.4572)
			(stroke
				(width 0.1)
				(type default)
			)
			(layer "B.Fab")
		)
		(pad "1" smd rect
			(at 0.7366 0)
			(size 0.7112 0.8128)
			(layers "B.Cu" "B.Mask" "B.Paste")
			(net "P0V8_SERDES_VDDA_PEX1")
		)
		(pad "2" smd rect
			(at -0.7366 0)
			(size 0.7112 0.8128)
			(layers "B.Cu" "B.Mask" "B.Paste")
			(net "GND")
		)
	)
	(footprint ""
		(layer "B.Cu")
		(at 299.00118 -305.399948 -90)
		(property "Reference" "C3317"
			(at 0 0 90)
			(layer "B.SilkS")
			(hide yes)
			(effects
				(font
					(size 1.27 1.27)
				)
				(justify mirror)
			)
		)
		(property "Value" ""
			(at 0 0 90)
			(layer "B.Fab")
			(effects
				(font
					(size 1.27 1.27)
				)
				(justify mirror)
			)
		)
		(duplicate_pad_numbers_are_jumpers no)
		(fp_line
			(start -0.299974 0.150114)
			(end 0.299974 0.150114)
			(stroke
				(width 0.1)
				(type default)
			)
			(layer "B.Fab")
		)
		(fp_line
			(start 0.299974 0.150114)
			(end 0.299974 -0.150114)
			(stroke
				(width 0.1)
				(type default)
			)
			(layer "B.Fab")
		)
		(fp_line
			(start -0.299974 -0.150114)
			(end -0.299974 0.150114)
			(stroke
				(width 0.1)
				(type default)
			)
			(layer "B.Fab")
		)
		(fp_line
			(start 0.299974 -0.150114)
			(end -0.299974 -0.150114)
			(stroke
				(width 0.1)
				(type default)
			)
			(layer "B.Fab")
		)
		(pad "1" smd rect
			(at 0.2667 0 90)
			(size 0.3048 0.381)
			(layers "B.Cu" "B.Mask" "B.Paste")
			(net "P1V25_SERDES_VDDPLL_PEX2")
		)
		(pad "2" smd rect
			(at -0.2667 0 90)
			(size 0.3048 0.381)
			(layers "B.Cu" "B.Mask" "B.Paste")
			(net "GND")
		)
	)
	(footprint ""
		(layer "B.Cu")
		(at 106.281474 -337.402932 90)
		(property "Reference" "R1232"
			(at 0 0 90)
			(layer "B.SilkS")
			(hide yes)
			(effects
				(font
					(size 1.27 1.27)
				)
				(justify mirror)
			)
		)
		(property "Value" ""
			(at 0 0 90)
			(layer "B.Fab")
			(effects
				(font
					(size 1.27 1.27)
				)
				(justify mirror)
			)
		)
		(duplicate_pad_numbers_are_jumpers no)
		(fp_line
			(start 0.7874 -0.4064)
			(end -0.7874 -0.4064)
			(stroke
				(width 0.1524)
				(type default)
			)
			(layer "B.SilkS")
		)
		(fp_line
			(start -0.7874 -0.4064)
			(end -0.7874 0.4064)
			(stroke
				(width 0.1524)
				(type default)
			)
			(layer "B.SilkS")
		)
		(fp_line
			(start 0.7874 0.4064)
			(end 0.7874 -0.4064)
			(stroke
				(width 0.1524)
				(type default)
			)
			(layer "B.SilkS")
		)
		(fp_line
			(start -0.7874 0.4064)
			(end 0.7874 0.4064)
			(stroke
				(width 0.1524)
				(type default)
			)
			(layer "B.SilkS")
		)
		(fp_line
			(start 0.67945 -0.305054)
			(end 0.12065 -0.305054)
			(stroke
				(width 0.1)
				(type default)
			)
			(layer "B.Fab")
		)
		(fp_line
			(start 0.12065 -0.305054)
			(end 0.12065 -0.2794)
			(stroke
				(width 0.1)
				(type default)
			)
			(layer "B.Fab")
		)
		(fp_line
			(start -0.12065 -0.3048)
			(end -0.67945 -0.3048)
			(stroke
				(width 0.1)
				(type default)
			)
			(layer "B.Fab")
		)
		(fp_line
			(start -0.67945 -0.3048)
			(end -0.67945 0.3048)
			(stroke
				(width 0.1)
				(type default)
			)
			(layer "B.Fab")
		)
		(fp_line
			(start 0.12065 -0.2794)
			(end -0.12065 -0.2794)
			(stroke
				(width 0.1)
				(type default)
			)
			(layer "B.Fab")
		)
		(fp_line
			(start -0.12065 -0.2794)
			(end -0.12065 -0.3048)
			(stroke
				(width 0.1)
				(type default)
			)
			(layer "B.Fab")
		)
		(fp_line
			(start 0.12065 0.2794)
			(end 0.12065 0.3048)
			(stroke
				(width 0.1)
				(type default)
			)
			(layer "B.Fab")
		)
		(fp_line
			(start -0.120396 0.2794)
			(end 0.12065 0.2794)
			(stroke
				(width 0.1)
				(type default)
			)
			(layer "B.Fab")
		)
		(fp_line
			(start 0.67945 0.3048)
			(end 0.67945 -0.305054)
			(stroke
				(width 0.1)
				(type default)
			)
			(layer "B.Fab")
		)
		(fp_line
			(start 0.12065 0.3048)
			(end 0.67945 0.3048)
			(stroke
				(width 0.1)
				(type default)
			)
			(layer "B.Fab")
		)
		(fp_line
			(start -0.120396 0.3048)
			(end -0.120396 0.2794)
			(stroke
				(width 0.1)
				(type default)
			)
			(layer "B.Fab")
		)
		(fp_line
			(start -0.67945 0.3048)
			(end -0.120396 0.3048)
			(stroke
				(width 0.1)
				(type default)
			)
			(layer "B.Fab")
		)
		(pad "1" smd circle
			(at 0.40005 0 270)
			(size 0 0)
			(layers "B.Cu" "B.Mask" "B.Paste")
			(net "CLK_100M_DB800ZL_PEX3_S0_R_DN")
		)
		(pad "2" smd circle
			(at -0.40005 0 270)
			(size 0 0)
			(layers "B.Cu" "B.Mask" "B.Paste")
			(net "CLK_100M_DB800ZL_PEX3_S0_DN")
		)
	)
	(footprint ""
		(layer "B.Cu")
		(at 142.806674 -214.959184 -90)
		(property "Reference" "R991"
			(at 0 0 90)
			(layer "B.SilkS")
			(hide yes)
			(effects
				(font
					(size 1.27 1.27)
				)
				(justify mirror)
			)
		)
		(property "Value" ""
			(at 0 0 90)
			(layer "B.Fab")
			(effects
				(font
					(size 1.27 1.27)
				)
				(justify mirror)
			)
		)
		(duplicate_pad_numbers_are_jumpers no)
		(fp_line
			(start -0.7874 0.4064)
			(end 0.7874 0.4064)
			(stroke
				(width 0.1524)
				(type default)
			)
			(layer "B.SilkS")
		)
		(fp_line
			(start 0.7874 0.4064)
			(end 0.7874 -0.4064)
			(stroke
				(width 0.1524)
				(type default)
			)
			(layer "B.SilkS")
		)
		(fp_line
			(start -0.7874 -0.4064)
			(end -0.7874 0.4064)
			(stroke
				(width 0.1524)
				(type default)
			)
			(layer "B.SilkS")
		)
		(fp_line
			(start 0.7874 -0.4064)
			(end -0.7874 -0.4064)
			(stroke
				(width 0.1524)
				(type default)
			)
			(layer "B.SilkS")
		)
		(fp_line
			(start -0.67945 0.3048)
			(end -0.120396 0.3048)
			(stroke
				(width 0.1)
				(type default)
			)
			(layer "B.Fab")
		)
		(fp_line
			(start -0.120396 0.3048)
			(end -0.120396 0.2794)
			(stroke
				(width 0.1)
				(type default)
			)
			(layer "B.Fab")
		)
		(fp_line
			(start 0.12065 0.3048)
			(end 0.67945 0.3048)
			(stroke
				(width 0.1)
				(type default)
			)
			(layer "B.Fab")
		)
		(fp_line
			(start 0.67945 0.3048)
			(end 0.67945 -0.305054)
			(stroke
				(width 0.1)
				(type default)
			)
			(layer "B.Fab")
		)
		(fp_line
			(start -0.120396 0.2794)
			(end 0.12065 0.2794)
			(stroke
				(width 0.1)
				(type default)
			)
			(layer "B.Fab")
		)
		(fp_line
			(start 0.12065 0.2794)
			(end 0.12065 0.3048)
			(stroke
				(width 0.1)
				(type default)
			)
			(layer "B.Fab")
		)
		(fp_line
			(start -0.12065 -0.2794)
			(end -0.12065 -0.3048)
			(stroke
				(width 0.1)
				(type default)
			)
			(layer "B.Fab")
		)
		(fp_line
			(start 0.12065 -0.2794)
			(end -0.12065 -0.2794)
			(stroke
				(width 0.1)
				(type default)
			)
			(layer "B.Fab")
		)
		(fp_line
			(start -0.67945 -0.3048)
			(end -0.67945 0.3048)
			(stroke
				(width 0.1)
				(type default)
			)
			(layer "B.Fab")
		)
		(fp_line
			(start -0.12065 -0.3048)
			(end -0.67945 -0.3048)
			(stroke
				(width 0.1)
				(type default)
			)
			(layer "B.Fab")
		)
		(fp_line
			(start 0.12065 -0.305054)
			(end 0.12065 -0.2794)
			(stroke
				(width 0.1)
				(type default)
			)
			(layer "B.Fab")
		)
		(fp_line
			(start 0.67945 -0.305054)
			(end 0.12065 -0.305054)
			(stroke
				(width 0.1)
				(type default)
			)
			(layer "B.Fab")
		)
		(pad "1" smd circle
			(at 0.40005 0 90)
			(size 0 0)
			(layers "B.Cu" "B.Mask" "B.Paste")
			(net "UART_PEX2_CLI_BUF_R_RX")
		)
		(pad "2" smd circle
			(at -0.40005 0 90)
			(size 0 0)
			(layers "B.Cu" "B.Mask" "B.Paste")
			(net "UART_PEX2_CLI_BUF_RX")
		)
	)
	(footprint ""
		(layer "B.Cu")
		(at 394.164312 -144.421352 180)
		(property "Reference" "C940"
			(at 0 0 0)
			(layer "B.SilkS")
			(hide yes)
			(effects
				(font
					(size 1.27 1.27)
				)
				(justify mirror)
			)
		)
		(property "Value" ""
			(at 0 0 0)
			(layer "B.Fab")
			(effects
				(font
					(size 1.27 1.27)
				)
				(justify mirror)
			)
		)
		(duplicate_pad_numbers_are_jumpers no)
		(fp_line
			(start 0.299974 0.150114)
			(end 0.299974 -0.150114)
			(stroke
				(width 0.1)
				(type default)
			)
			(layer "B.Fab")
		)
		(fp_line
			(start 0.299974 -0.150114)
			(end -0.299974 -0.150114)
			(stroke
				(width 0.1)
				(type default)
			)
			(layer "B.Fab")
		)
		(fp_line
			(start -0.299974 0.150114)
			(end 0.299974 0.150114)
			(stroke
				(width 0.1)
				(type default)
			)
			(layer "B.Fab")
		)
		(fp_line
			(start -0.299974 -0.150114)
			(end -0.299974 0.150114)
			(stroke
				(width 0.1)
				(type default)
			)
			(layer "B.Fab")
		)
		(pad "1" smd rect
			(at 0.2667 0)
			(size 0.3048 0.381)
			(layers "B.Cu" "B.Mask" "B.Paste")
			(net "P12V_NIC6")
		)
		(pad "2" smd rect
			(at -0.2667 0)
			(size 0.3048 0.381)
			(layers "B.Cu" "B.Mask" "B.Paste")
			(net "GND")
		)
	)
)
